(kicad_pcb
	(version 20241229)
	(generator "pcbnew")
	(generator_version "9.0")
	(general
		(thickness 1.6296)
		(legacy_teardrops no)
	)
	(paper "A3")
	(title_block
		(title "Thunderbolt to 10GbE adapter")
		(date "2026-04-21")
		(rev "1.1.0")
		(company "Antmicro Ltd")
		(comment 1 "www.antmicro.com")
		(comment 9 "footprints 356-359 of 703")
	)
	(layers
		(0 "F.Cu" signal)
		(4 "In1.Cu" signal)
		(6 "In2.Cu" signal)
		(8 "In3.Cu" signal)
		(10 "In4.Cu" signal)
		(12 "In5.Cu" signal)
		(14 "In6.Cu" signal)
		(2 "B.Cu" signal)
		(9 "F.Adhes" user "F.Adhesive")
		(11 "B.Adhes" user "B.Adhesive")
		(13 "F.Paste" user)
		(15 "B.Paste" user)
		(5 "F.SilkS" user "F.Silkscreen")
		(7 "B.SilkS" user "B.Silkscreen")
		(1 "F.Mask" user)
		(3 "B.Mask" user)
		(17 "Dwgs.User" user "User.Drawings")
		(19 "Cmts.User" user "User.Comments")
		(21 "Eco1.User" user "User.Eco1")
		(23 "Eco2.User" user "User.Eco2")
		(25 "Edge.Cuts" user)
		(27 "Margin" user)
		(31 "F.CrtYd" user "F.Courtyard")
		(29 "B.CrtYd" user "B.Courtyard")
		(35 "F.Fab" user)
		(33 "B.Fab" user)
	)
	(footprint "antmicro-footprints:C_0603_1608Metric"
		(layer "F.Cu")
		(at 151.955 94.024999)
		(descr "Capacitor SMD 0603")
		(tags "capacitor 0603")
		(property "Reference" "C172"
			(at 23.294999 19.625001 0)
			(layer "F.SilkS")
			(effects
				(font
					(size 0.7 0.7)
					(thickness 0.15)
				)
			)
		)
		(property "Value" "C_47u_0603"
			(at -1.42757 1.770288 0)
			(layer "F.Fab")
			(effects
				(font
					(size 0.7 0.7)
					(thickness 0.15)
				)
				(justify left bottom)
			)
		)
		(property "Datasheet" "https://www.murata.com/products/productdetail?partno=GRM188R60J476ME15%23"
			(at 0 0 0)
			(layer "F.Fab")
			(hide yes)
			(effects
				(font
					(size 1.27 1.27)
					(thickness 0.15)
				)
			)
		)
		(property "Description" "SMD Multilayer Ceramic Capacitor, 47 µF, 6.3 V, 0603 [1608 Metric], ± 20%, X5R, GRM Series"
			(at 0 0 0)
			(layer "F.Fab")
			(hide yes)
			(effects
				(font
					(size 1.27 1.27)
					(thickness 0.15)
				)
			)
		)
		(property "MPN" "GRM188R60J476ME15D"
			(at 0 0 0)
			(unlocked yes)
			(layer "F.Fab")
			(hide yes)
			(effects
				(font
					(size 1 1)
					(thickness 0.15)
				)
			)
		)
		(property "Manufacturer" "Murata"
			(at 0 0 0)
			(unlocked yes)
			(layer "F.Fab")
			(hide yes)
			(effects
				(font
					(size 1 1)
					(thickness 0.15)
				)
			)
		)
		(property "License" "Apache-2.0"
			(at 0 0 0)
			(unlocked yes)
			(layer "F.Fab")
			(hide yes)
			(effects
				(font
					(size 1 1)
					(thickness 0.15)
				)
			)
		)
		(property "Author" "Antmicro"
			(at 0 0 0)
			(unlocked yes)
			(layer "F.Fab")
			(hide yes)
			(effects
				(font
					(size 1 1)
					(thickness 0.15)
				)
			)
		)
		(property "Val" "47u"
			(at 0 0 0)
			(unlocked yes)
			(layer "F.Fab")
			(hide yes)
			(effects
				(font
					(size 1 1)
					(thickness 0.15)
				)
			)
		)
		(property "Voltage" ""
			(at 0 0 0)
			(unlocked yes)
			(layer "F.Fab")
			(hide yes)
			(effects
				(font
					(size 1 1)
					(thickness 0.15)
				)
			)
		)
		(property "Dielectric" ""
			(at 0 0 0)
			(unlocked yes)
			(layer "F.Fab")
			(hide yes)
			(effects
				(font
					(size 1 1)
					(thickness 0.15)
				)
			)
		)
		(sheetname "/X710-AT2 power/")
		(sheetfile "x710-at2-power.kicad_sch")
		(attr smd)
		(fp_line
			(start -0.15 -0.4)
			(end 0.15 -0.4)
			(stroke
				(width 0.15)
				(type solid)
			)
			(layer "F.SilkS")
		)
		(fp_line
			(start -0.15 0.4)
			(end 0.15 0.4)
			(stroke
				(width 0.15)
				(type solid)
			)
			(layer "F.SilkS")
		)
		(fp_rect
			(start -1.25 -0.65)
			(end 1.25 0.65)
			(stroke
				(width 0.05)
				(type solid)
			)
			(fill no)
			(layer "F.CrtYd")
		)
		(fp_rect
			(start -0.8 -0.4)
			(end 0.8 0.4)
			(stroke
				(width 0.15)
				(type solid)
			)
			(fill no)
			(layer "F.Fab")
		)
		(fp_text user "License: Apache-2.0"
			(at -1.682 5.895 0)
			(layer "F.Fab")
			(effects
				(font
					(size 0.7 0.7)
					(thickness 0.15)
				)
				(justify left bottom)
			)
		)
		(fp_text user "Author: Antmicro"
			(at -1.682 4.894 0)
			(layer "F.Fab")
			(effects
				(font
					(size 0.7 0.7)
					(thickness 0.15)
				)
				(justify left bottom)
			)
		)
		(fp_text user "${REFERENCE}"
			(at -1.682 3.895 0)
			(layer "F.Fab")
			(effects
				(font
					(size 0.7 0.7)
					(thickness 0.15)
				)
				(justify left bottom)
			)
		)
		(pad "1" smd roundrect
			(at -0.7 0)
			(size 0.8 1)
			(layers "F.Cu" "F.Mask" "F.Paste")
			(roundrect_rratio 0.2)
			(net 23 "GND")
			(pintype "passive")
		)
		(pad "2" smd roundrect
			(at 0.7 0)
			(size 0.8 1)
			(layers "F.Cu" "F.Mask" "F.Paste")
			(roundrect_rratio 0.2)
			(net 12 "XFI_VDD")
			(pintype "passive")
		)
	)
	(footprint "antmicro-footprints:TSSOP-8_3x3mm_P0.65mm"
		(layer "F.Cu")
		(at 172 77)
		(property "Reference" "U16"
			(at -3.4 -1.8 0)
			(layer "F.SilkS")
			(effects
				(font
					(size 0.7 0.7)
					(thickness 0.15)
				)
				(justify left bottom)
			)
		)
		(property "Value" "NTS0102_TSSOP"
			(at 0 2.8 0)
			(layer "F.Fab")
			(effects
				(font
					(size 0.7 0.7)
					(thickness 0.15)
				)
				(justify left bottom)
			)
		)
		(property "Datasheet" "https://www.mouser.com/datasheet/2/302/NTS0102-1127324.pdf"
			(at 0 0 0)
			(layer "F.Fab")
			(hide yes)
			(effects
				(font
					(size 1.27 1.27)
					(thickness 0.15)
				)
			)
		)
		(property "Description" "Transceiver, 1.65 V to 3.6 V, TSSOP-8"
			(at 0 0 0)
			(layer "F.Fab")
			(hide yes)
			(effects
				(font
					(size 1.27 1.27)
					(thickness 0.15)
				)
			)
		)
		(property "MPN" "NTS0102DP"
			(at 0 0 0)
			(unlocked yes)
			(layer "F.Fab")
			(hide yes)
			(effects
				(font
					(size 1 1)
					(thickness 0.15)
				)
			)
		)
		(property "Manufacturer" "NXP"
			(at 0 0 0)
			(unlocked yes)
			(layer "F.Fab")
			(hide yes)
			(effects
				(font
					(size 1 1)
					(thickness 0.15)
				)
			)
		)
		(property "Author" "Antmicro"
			(at 0 0 0)
			(unlocked yes)
			(layer "F.Fab")
			(hide yes)
			(effects
				(font
					(size 1 1)
					(thickness 0.15)
				)
			)
		)
		(property "License" "Apache-2.0"
			(at 0 0 0)
			(unlocked yes)
			(layer "F.Fab")
			(hide yes)
			(effects
				(font
					(size 1 1)
					(thickness 0.15)
				)
			)
		)
		(sheetname "/X710-AT2 Misc/")
		(sheetfile "x710-at2-mics.kicad_sch")
		(attr smd)
		(fp_line
			(start -1.55 1.561)
			(end 1.552 1.561)
			(stroke
				(width 0.15)
				(type solid)
			)
			(layer "F.SilkS")
		)
		(fp_line
			(start -1.525 -1.537)
			(end 1.552 -1.539)
			(stroke
				(width 0.15)
				(type solid)
			)
			(layer "F.SilkS")
		)
		(fp_circle
			(center -1.87 -1.4)
			(end -1.82 -1.4)
			(stroke
				(width 0.15)
				(type solid)
			)
			(fill yes)
			(layer "F.SilkS")
		)
		(fp_rect
			(start -3.15 -1.789)
			(end 3.15 1.811)
			(stroke
				(width 0.05)
				(type solid)
			)
			(fill no)
			(layer "F.CrtYd")
		)
		(fp_line
			(start -1.55 -0.937)
			(end -1.55 1.561)
			(stroke
				(width 0.15)
				(type solid)
			)
			(layer "F.Fab")
		)
		(fp_line
			(start -1.55 -0.937)
			(end -0.949 -1.539)
			(stroke
				(width 0.15)
				(type solid)
			)
			(layer "F.Fab")
		)
		(fp_line
			(start -1.55 1.561)
			(end 1.552 1.561)
			(stroke
				(width 0.15)
				(type solid)
			)
			(layer "F.Fab")
		)
		(fp_line
			(start -0.949 -1.539)
			(end 1.552 -1.539)
			(stroke
				(width 0.15)
				(type solid)
			)
			(layer "F.Fab")
		)
		(fp_line
			(start 1.552 -1.539)
			(end 1.552 1.561)
			(stroke
				(width 0.15)
				(type solid)
			)
			(layer "F.Fab")
		)
		(fp_text user "${REFERENCE}"
			(at -1.789 6.58 0)
			(layer "F.Fab")
			(effects
				(font
					(size 0.7 0.7)
					(thickness 0.15)
				)
				(justify left bottom)
			)
		)
		(fp_text user "License: Apache-2.0"
			(at -1.789 8.98 0)
			(layer "F.Fab")
			(effects
				(font
					(size 0.7 0.7)
					(thickness 0.15)
				)
				(justify left bottom)
			)
		)
		(fp_text user "Author: Antmicro"
			(at -1.789 7.78 0)
			(layer "F.Fab")
			(effects
				(font
					(size 0.7 0.7)
					(thickness 0.15)
				)
				(justify left bottom)
			)
		)
		(pad "1" smd roundrect
			(at -2.148 -0.962)
			(size 1.47 0.4)
			(layers "F.Cu" "F.Mask" "F.Paste")
			(roundrect_rratio 0.25)
			(net 122 "/X710-AT2 10GbE/MDIO0_I2C0.MDIO")
			(pinfunction "B_{2}")
			(pintype "bidirectional")
		)
		(pad "2" smd roundrect
			(at -2.148 -0.313)
			(size 1.47 0.4)
			(layers "F.Cu" "F.Mask" "F.Paste")
			(roundrect_rratio 0.25)
			(net 23 "GND")
			(pinfunction "GND")
			(pintype "power_in")
		)
		(pad "3" smd roundrect
			(at -2.148 0.338)
			(size 1.47 0.4)
			(layers "F.Cu" "F.Mask" "F.Paste")
			(roundrect_rratio 0.25)
			(net 18 "+1V88")
			(pinfunction "VCC_{A}")
			(pintype "power_in")
		)
		(pad "4" smd roundrect
			(at -2.148 0.987)
			(size 1.47 0.4)
			(layers "F.Cu" "F.Mask" "F.Paste")
			(roundrect_rratio 0.25)
			(net 147 "/X710-AT2 Misc/MDIO.MDIO")
			(pinfunction "A_{2}")
			(pintype "bidirectional")
		)
		(pad "5" smd roundrect
			(at 2.151 0.987)
			(size 1.47 0.4)
			(layers "F.Cu" "F.Mask" "F.Paste")
			(roundrect_rratio 0.25)
			(net 148 "/X710-AT2 Misc/MDIO.MDC")
			(pinfunction "A_{1}")
			(pintype "bidirectional")
		)
		(pad "6" smd roundrect
			(at 2.151 0.338)
			(size 1.47 0.4)
			(layers "F.Cu" "F.Mask" "F.Paste")
			(roundrect_rratio 0.25)
			(net 18 "+1V88")
			(pinfunction "OE")
			(pintype "input")
		)
		(pad "7" smd roundrect
			(at 2.151 -0.313)
			(size 1.47 0.4)
			(layers "F.Cu" "F.Mask" "F.Paste")
			(roundrect_rratio 0.25)
			(net 7 "+3V3")
			(pinfunction "VCC_{B}")
			(pintype "power_in")
		)
		(pad "8" smd roundrect
			(at 2.151 -0.962)
			(size 1.47 0.4)
			(layers "F.Cu" "F.Mask" "F.Paste")
			(roundrect_rratio 0.25)
			(net 125 "/X710-AT2 10GbE/MDIO0_I2C0.MDC")
			(pinfunction "B_{1}")
			(pintype "bidirectional")
		)
	)
	(footprint "antmicro-footprints:C_0603_1608Metric"
		(layer "F.Cu")
		(at 149.305 94.024999 180)
		(descr "Capacitor SMD 0603")
		(tags "capacitor 0603")
		(property "Reference" "C177"
			(at -23.294999 -19.625001 180)
			(layer "F.SilkS")
			(effects
				(font
					(size 0.7 0.7)
					(thickness 0.15)
				)
			)
		)
		(property "Value" "C_10u_10V_X7R_0603"
			(at -1.42757 1.770288 180)
			(layer "F.Fab")
			(effects
				(font
					(size 0.7 0.7)
					(thickness 0.15)
				)
				(justify left bottom)
			)
		)
		(property "Datasheet" "https://www.murata.com/products/productdetail?partno=GRM188Z71A106KA73%23"
			(at 0 0 180)
			(layer "F.Fab")
			(hide yes)
			(effects
				(font
					(size 1.27 1.27)
					(thickness 0.15)
				)
			)
		)
		(property "Description" "SMD Multilayer Ceramic Capacitor,  10µF, 10V, 0603, ±10%, X7R"
			(at 0 0 180)
			(layer "F.Fab")
			(hide yes)
			(effects
				(font
					(size 1.27 1.27)
					(thickness 0.15)
				)
			)
		)
		(property "MPN" "GRM188Z71A106KA73D"
			(at 0 0 180)
			(unlocked yes)
			(layer "F.Fab")
			(hide yes)
			(effects
				(font
					(size 1 1)
					(thickness 0.15)
				)
			)
		)
		(property "Val" "10u"
			(at 0 0 180)
			(unlocked yes)
			(layer "F.Fab")
			(hide yes)
			(effects
				(font
					(size 1 1)
					(thickness 0.15)
				)
			)
		)
		(property "Voltage" "10V"
			(at 0 0 180)
			(unlocked yes)
			(layer "F.Fab")
			(hide yes)
			(effects
				(font
					(size 1 1)
					(thickness 0.15)
				)
			)
		)
		(property "Dielectric" "X7R"
			(at 0 0 180)
			(unlocked yes)
			(layer "F.Fab")
			(hide yes)
			(effects
				(font
					(size 1 1)
					(thickness 0.15)
				)
			)
		)
		(property "Manufacturer" "Murata"
			(at 0 0 180)
			(unlocked yes)
			(layer "F.Fab")
			(hide yes)
			(effects
				(font
					(size 1 1)
					(thickness 0.15)
				)
			)
		)
		(property "License" "Apache-2.0"
			(at 0 0 180)
			(unlocked yes)
			(layer "F.Fab")
			(hide yes)
			(effects
				(font
					(size 1 1)
					(thickness 0.15)
				)
			)
		)
		(property "Author" "Antmicro"
			(at 0 0 180)
			(unlocked yes)
			(layer "F.Fab")
			(hide yes)
			(effects
				(font
					(size 1 1)
					(thickness 0.15)
				)
			)
		)
		(sheetname "/X710-AT2 power/")
		(sheetfile "x710-at2-power.kicad_sch")
		(attr smd)
		(fp_line
			(start -0.15 0.4)
			(end 0.15 0.4)
			(stroke
				(width 0.15)
				(type solid)
			)
			(layer "F.SilkS")
		)
		(fp_line
			(start -0.15 -0.4)
			(end 0.15 -0.4)
			(stroke
				(width 0.15)
				(type solid)
			)
			(layer "F.SilkS")
		)
		(fp_rect
			(start -1.25 -0.65)
			(end 1.25 0.65)
			(stroke
				(width 0.05)
				(type solid)
			)
			(fill no)
			(layer "F.CrtYd")
		)
		(fp_rect
			(start -0.8 -0.4)
			(end 0.8 0.4)
			(stroke
				(width 0.15)
				(type solid)
			)
			(fill no)
			(layer "F.Fab")
		)
		(fp_text user "License: Apache-2.0"
			(at -1.682 5.895 180)
			(layer "F.Fab")
			(effects
				(font
					(size 0.7 0.7)
					(thickness 0.15)
				)
				(justify left bottom)
			)
		)
		(fp_text user "${REFERENCE}"
			(at -1.682 3.895 180)
			(layer "F.Fab")
			(effects
				(font
					(size 0.7 0.7)
					(thickness 0.15)
				)
				(justify left bottom)
			)
		)
		(fp_text user "Author: Antmicro"
			(at -1.682 4.894 180)
			(layer "F.Fab")
			(effects
				(font
					(size 0.7 0.7)
					(thickness 0.15)
				)
				(justify left bottom)
			)
		)
		(pad "1" smd roundrect
			(at -0.7 0 180)
			(size 0.8 1)
			(layers "F.Cu" "F.Mask" "F.Paste")
			(roundrect_rratio 0.2)
			(net 23 "GND")
			(pintype "passive")
		)
		(pad "2" smd roundrect
			(at 0.7 0 180)
			(size 0.8 1)
			(layers "F.Cu" "F.Mask" "F.Paste")
			(roundrect_rratio 0.2)
			(net 10 "AVDDH")
			(pintype "passive")
		)
	)
	(footprint "antmicro-footprints:C_0402_1005Metric"
		(layer "F.Cu")
		(at 147.555 97.375 -90)
		(descr "Capacitor SMD 0402")
		(tags "capacitor SMD 0402")
		(property "Reference" "C161"
			(at 19.625001 -23.294999 270)
			(layer "F.SilkS")
			(effects
				(font
					(size 0.7 0.7)
					(thickness 0.15)
				)
			)
		)
		(property "Value" "C_100n_0402"
			(at -1.022927 2.155213 270)
			(layer "F.Fab")
			(effects
				(font
					(size 0.7 0.7)
					(thickness 0.15)
				)
				(justify left bottom)
			)
		)
		(property "Datasheet" "https://www.murata.com/products/productdetail?partno=GRM155R61H104KE14%23"
			(at 0 0 270)
			(layer "F.Fab")
			(hide yes)
			(effects
				(font
					(size 1.27 1.27)
					(thickness 0.15)
				)
			)
		)
		(property "Description" "SMD Multilayer Ceramic Capacitor, 0.1 µF, 50 V, 0402 [1005 Metric], ± 10%, X5R, GRM Series"
			(at 0 0 270)
			(layer "F.Fab")
			(hide yes)
			(effects
				(font
					(size 1.27 1.27)
					(thickness 0.15)
				)
			)
		)
		(property "MPN" "GRM155R61H104KE14D"
			(at 0 0 270)
			(unlocked yes)
			(layer "F.Fab")
			(hide yes)
			(effects
				(font
					(size 1 1)
					(thickness 0.15)
				)
			)
		)
		(property "Val" "100n"
			(at 0 0 270)
			(unlocked yes)
			(layer "F.Fab")
			(hide yes)
			(effects
				(font
					(size 1 1)
					(thickness 0.15)
				)
			)
		)
		(property "Voltage" "50V"
			(at 0 0 270)
			(unlocked yes)
			(layer "F.Fab")
			(hide yes)
			(effects
				(font
					(size 1 1)
					(thickness 0.15)
				)
			)
		)
		(property "Dielectric" "X5R"
			(at 0 0 270)
			(unlocked yes)
			(layer "F.Fab")
			(hide yes)
			(effects
				(font
					(size 1 1)
					(thickness 0.15)
				)
			)
		)
		(property "Manufacturer" "Murata"
			(at 0 0 270)
			(unlocked yes)
			(layer "F.Fab")
			(hide yes)
			(effects
				(font
					(size 1 1)
					(thickness 0.15)
				)
			)
		)
		(property "License" "Apache-2.0"
			(at 0 0 270)
			(unlocked yes)
			(layer "F.Fab")
			(hide yes)
			(effects
				(font
					(size 1 1)
					(thickness 0.15)
				)
			)
		)
		(property "Author" "Antmicro"
			(at 0 0 270)
			(unlocked yes)
			(layer "F.Fab")
			(hide yes)
			(effects
				(font
					(size 1 1)
					(thickness 0.15)
				)
			)
		)
		(sheetname "/X710-AT2 power/")
		(sheetfile "x710-at2-power.kicad_sch")
		(attr smd)
		(fp_rect
			(start -0.925 -0.47)
			(end 0.925 0.47)
			(stroke
				(width 0.05)
				(type default)
			)
			(fill no)
			(layer "F.CrtYd")
		)
		(fp_line
			(start -0.494 0.248)
			(end -0.494 -0.25)
			(stroke
				(width 0.15)
				(type solid)
			)
			(layer "F.Fab")
		)
		(fp_line
			(start 0.504 0.248)
			(end -0.494 0.248)
			(stroke
				(width 0.15)
				(type solid)
			)
			(layer "F.Fab")
		)
		(fp_line
			(start -0.494 -0.25)
			(end 0.504 -0.25)
			(stroke
				(width 0.15)
				(type solid)
			)
			(layer "F.Fab")
		)
		(fp_line
			(start 0.504 -0.25)
			(end 0.504 0.248)
			(stroke
				(width 0.15)
				(type solid)
			)
			(layer "F.Fab")
		)
		(fp_text user "Author: Antmicro"
			(at -0.939 3.399 270)
			(layer "F.Fab")
			(effects
				(font
					(size 0.7 0.7)
					(thickness 0.15)
				)
				(justify left bottom)
			)
		)
		(fp_text user "${REFERENCE}"
			(at -0.939 4.599 270)
			(layer "F.Fab")
			(effects
				(font
					(size 0.7 0.7)
					(thickness 0.15)
				)
				(justify left bottom)
			)
		)
		(fp_text user "License: Apache-2.0"
			(at -0.939 5.799 270)
			(layer "F.Fab")
			(effects
				(font
					(size 0.7 0.7)
					(thickness 0.15)
				)
				(justify left bottom)
			)
		)
		(pad "1" smd roundrect
			(at -0.48 0 270)
			(size 0.59 0.64)
			(layers "F.Cu" "F.Mask" "F.Paste")
			(roundrect_rratio 0.25)
			(net 23 "GND")
			(pintype "passive")
		)
		(pad "2" smd roundrect
			(at 0.48 0 270)
			(size 0.59 0.64)
			(layers "F.Cu" "F.Mask" "F.Paste")
			(roundrect_rratio 0.25)
			(net 18 "+1V88")
			(pintype "passive")
		)
	)
)
